# S9S_MB_2U (Grand Teton) — schematic netlist excerpt (pin names and nets, part order shuffled) for the footprints in the layout excerpt that follows; sources: Cadence DE-HDL packaged netlist, KiCad conversion of 03242023_DA0F0TMBIJ0_F0T_Motherboard_J_brd_V01_OCP.brd

J7  SCONN288_ADR50017P130CC  SCONN288_ADR50017-P130CC IO  pkg DDR288S_1-1VXB  page 88
  VIN_BULK0  = P12V_S3_AUX_CPU0_NVDIMM
  RFU0  = TP_CHD_CPU0_DIMM1_FRU_0
  VIN_MGMT  = P3V3_AUX
  HSCL  = I3C_SPD_DDRABCD_CPU0_LVC1_SCL_6
  HSDA  = I3C_SPD_DDRABCD_CPU0_LVC1_SDA
  VSS0  = GND
  DQ0_A  = M_D_CPU0_SA_DQ<0>
  VSS1  = GND
  DQ1_A  = M_D_CPU0_SA_DQ<1>
  VSS2  = GND
  DQS0_A_T  = M_D_CPU0_SA_DQS_DP<0>
  DQS0_A_C  = M_D_CPU0_SA_DQS_DN<0>
  VSS3  = GND
  DQ4_A  = M_D_CPU0_SA_DQ<4>
  VSS4  = GND
  DQ5_A  = M_D_CPU0_SA_DQ<5>
  VSS5  = GND
  DQ8_A  = M_D_CPU0_SA_DQ<8>
  VSS6  = GND
  DQ9_A  = M_D_CPU0_SA_DQ<9>
  VSS7  = GND
  DQS1_A_T  = M_D_CPU0_SA_DQS_DP<1>
  DQS1_A_C  = M_D_CPU0_SA_DQS_DN<1>
  VSS8  = GND
  DQ12_A  = M_D_CPU0_SA_DQ<12>
  VSS9  = GND
  DQ13_A  = M_D_CPU0_SA_DQ<13>
  VSS10  = GND
  DQ16_A  = M_D_CPU0_SA_DQ<16>
  VSS11  = GND
  DQ17_A  = M_D_CPU0_SA_DQ<17>
  VSS12  = GND
  DQS2_A_T  = M_D_CPU0_SA_DQS_DP<2>
  DQS2_A_C  = M_D_CPU0_SA_DQS_DN<2>
  VSS13  = GND
  DQ20_A  = M_D_CPU0_SA_DQ<20>
  VSS14  = GND
  DQ21_A  = M_D_CPU0_SA_DQ<21>
  VSS15  = GND
  DQ24_A  = M_D_CPU0_SA_DQ<24>
  VSS16  = GND
  DQ25_A  = M_D_CPU0_SA_DQ<25>
  VSS17  = GND
  DQS3_A_T  = M_D_CPU0_SA_DQS_DP<3>
  DQS3_A_C  = M_D_CPU0_SA_DQS_DN<3>
  VSS18  = GND
  DQ28_A  = M_D_CPU0_SA_DQ<28>
  VSS19  = GND
  DQ29_A  = M_D_CPU0_SA_DQ<29>
  VSS20  = GND
  CB0_A  = M_D_CPU0_SA_CB<0>
  VSS21  = GND
  CB1_A  = M_D_CPU0_SA_CB<1>
  VSS22  = GND
  DQS4_A_T  = M_D_CPU0_SA_DQS_DP<4>
  DQS4_A_C  = M_D_CPU0_SA_DQS_DN<4>
  VSS23  = GND
  CB4_A  = M_D_CPU0_SA_CB<4>
  VSS24  = GND
  CB5_A  = M_D_CPU0_SA_CB<5>
  VSS25  = GND
  ALERT_N  = M_D_CPU0_ALERT_N
  VSS26  = GND
  CS0_A_N  = M_D_CPU0_SA_CS_N<0>
  VSS27  = GND
  CA0_A  = M_D_CPU0_SA_CA<0>
  VSS28  = GND
  CA2_A  = M_D_CPU0_SA_CA<2>
  VSS29  = GND
  CA4_A  = M_D_CPU0_SA_CA<4>
  VSS30  = GND
  CA6_A  = M_D_CPU0_SA_CA<6>
  VSS31  = GND
  PAR_A  = M_D_CPU0_SA_PAR
  VSS32  = GND
  CA0_B  = M_D_CPU0_SB_CA<0>
  VSS33  = GND
  CA2_B  = M_D_CPU0_SB_CA<2>
  VSS34  = GND
  CA4_B  = M_D_CPU0_SB_CA<4>
  VSS35  = GND
  CA6_B  = M_D_CPU0_SB_CA<6>
  VSS36  = GND
  CS0_B_N  = M_D_CPU0_SB_CS_N<0>
  VSS37  = GND
  \lbd||rsp_a_n\  = M_D_CPU0_SA_RSP<0>
  \lbs||rsp_b_n\  = M_D_CPU0_SB_RSP<0>
  VSS38  = GND
  CB4_B  = M_D_CPU0_SB_CB<4>
  VSS39  = GND
  CB5_B  = M_D_CPU0_SB_CB<5>
  VSS40  = GND
  \dqs9_b_t||tdqs9_b_t||dbi4_b_n\  = M_D_CPU0_SB_DQS_DP<9>
  \dqs9_b_c||tdqs9_b_c\  = M_D_CPU0_SB_DQS_DN<9>
  VSS41  = GND
  CB0_B  = M_D_CPU0_SB_CB<0>
  VSS42  = GND
  CB1_B  = M_D_CPU0_SB_CB<1>
  VSS43  = GND
  DQ0_B  = M_D_CPU0_SB_DQ<0>
  VSS44  = GND
  DQ1_B  = M_D_CPU0_SB_DQ<1>
  VSS45  = GND
  DQS0_B_T  = M_D_CPU0_SB_DQS_DP<0>
  DQS0_B_C  = M_D_CPU0_SB_DQS_DN<0>
  VSS46  = GND
  DQ4_B  = M_D_CPU0_SB_DQ<4>
  VSS47  = GND
  DQ5_B  = M_D_CPU0_SB_DQ<5>
  VSS48  = GND
  DQ8_B  = M_D_CPU0_SB_DQ<8>
  VSS49  = GND
  DQ9_B  = M_D_CPU0_SB_DQ<9>
  VSS50  = GND
  DQS1_B_T  = M_D_CPU0_SB_DQS_DP<1>
  DQS1_B_C  = M_D_CPU0_SB_DQS_DN<1>
  VSS51  = GND
  DQ12_B  = M_D_CPU0_SB_DQ<12>
  VSS52  = GND
  DQ13_B  = M_D_CPU0_SB_DQ<13>
  VSS53  = GND
  DQ16_B  = M_D_CPU0_SB_DQ<16>
  VSS54  = GND
  DQ17_B  = M_D_CPU0_SB_DQ<17>
  VSS55  = GND
  DQS2_B_T  = M_D_CPU0_SB_DQS_DP<2>
  DQS2_B_C  = M_D_CPU0_SB_DQS_DN<2>
  VSS56  = GND
  DQ20_B  = M_D_CPU0_SB_DQ<20>
  VSS57  = GND
  DQ21_B  = M_D_CPU0_SB_DQ<21>
  VSS58  = GND
  DQ24_B  = M_D_CPU0_SB_DQ<24>
  VSS59  = GND
  DQ25_B  = M_D_CPU0_SB_DQ<25>
  VSS60  = GND
  DQS3_B_T  = M_D_CPU0_SB_DQS_DP<3>
  DQS3_B_C  = M_D_CPU0_SB_DQS_DN<3>
  VSS61  = GND
  DQ28_B  = M_D_CPU0_SB_DQ<28>
  VSS62  = GND
  DQ29_B  = M_D_CPU0_SB_DQ<29>
  VSS63  = GND
  RFU1  = TP_CHD_CPU0_DIMM1_FRU_1
  VIN_BULK1  = P12V_S3_AUX_CPU0_NVDIMM
  VIN_BULK2  = P12V_S3_AUX_CPU0_NVDIMM
  \pwr_good||fail_n\  = PWRGD_CHD_CPU0_DIMM1
  HSA  = PD_CHD_CPU0_DIMM1_SAA
  RFU2  = TP_CHD_CPU0_DIMM1_FRU_2
  RFU3  = TP_CHD_CPU0_DIMM1_FRU_3
  VSS64  = GND
  DQ2_A  = M_D_CPU0_SA_DQ<2>
  VSS65  = GND
  DQ3_A  = M_D_CPU0_SA_DQ<3>
  VSS66  = GND
  \dqs5_a_c||tdqs5_a_c||dqs5_a_t||tdqs5_a_t\  = M_D_CPU0_SA_DQS_DN<5>
  \dqs5_a_t||tdqs5_a_t\  = M_D_CPU0_SA_DQS_DP<5>
  VSS67  = GND
  DQ6_A  = M_D_CPU0_SA_DQ<6>
  VSS68  = GND
  DQ7_A  = M_D_CPU0_SA_DQ<7>
  VSS69  = GND
  DQ10_A  = M_D_CPU0_SA_DQ<10>
  VSS70  = GND
  DQ11_A  = M_D_CPU0_SA_DQ<11>
  VSS71  = GND
  \dqs6_a_c||tdqs6_a_c||dqs6_a_t||tdqs6_a_t\  = M_D_CPU0_SA_DQS_DN<6>
  \dqs6_a_t||tdqs6_a_t\  = M_D_CPU0_SA_DQS_DP<6>
  VSS72  = GND
  DQ14_A  = M_D_CPU0_SA_DQ<14>
  VSS73  = GND
  DQ15_A  = M_D_CPU0_SA_DQ<15>
  VSS74  = GND
  DQ18_A  = M_D_CPU0_SA_DQ<18>
  VSS75  = GND
  DQ19_A  = M_D_CPU0_SA_DQ<19>
  VSS76  = GND
  \dqs7_a_c||tdqs7_a_c\  = M_D_CPU0_SA_DQS_DN<7>
  \dqs7_a_t||tdqs7_a_t\  = M_D_CPU0_SA_DQS_DP<7>
  VSS77  = GND
  DQ22_A  = M_D_CPU0_SA_DQ<22>
  VSS78  = GND
  DQ23_A  = M_D_CPU0_SA_DQ<23>
  VSS79  = GND
  DQ26_A  = M_D_CPU0_SA_DQ<26>
  VSS80  = GND
  DQ27_A  = M_D_CPU0_SA_DQ<27>
  VSS81  = GND
  \dqs8_a_c||tdqs8_a_c\  = M_D_CPU0_SA_DQS_DN<8>
  \dqs8_a_t||tdqs8_a_t\  = M_D_CPU0_SA_DQS_DP<8>
  VSS82  = GND
  DQ30_A  = M_D_CPU0_SA_DQ<30>
  VSS83  = GND
  DQ31_A  = M_D_CPU0_SA_DQ<31>
  VSS84  = GND
  CB2_A  = M_D_CPU0_SA_CB<2>
  VSS85  = GND
  CB3_A  = M_D_CPU0_SA_CB<3>
  VSS86  = GND
  \dqs9_a_c||tdqs9_a_c\  = M_D_CPU0_SA_DQS_DN<9>
  \dqs9_a_t||tdqs9_a_t\  = M_D_CPU0_SA_DQS_DP<9>
  VSS87  = GND
  CB6_A  = M_D_CPU0_SA_CB<6>
  VSS88  = GND
  CB7_A  = M_D_CPU0_SA_CB<7>
  VSS89  = GND
  RESET_N  = RST_M_CD_CPU0_FPGA_N
  VSS90  = GND
  CS1_A_N  = M_D_CPU0_SA_CS_N<1>
  VSS91  = GND
  CA1_A  = M_D_CPU0_SA_CA<1>
  VSS92  = GND
  CA3_A  = M_D_CPU0_SA_CA<3>
  VSS93  = GND
  CA5_A  = M_D_CPU0_SA_CA<5>
  VSS94  = GND
  CK_T  = M_D_CPU0_CLK_DP<0>
  CK_C  = M_D_CPU0_CLK_DN<0>
  VSS95  = GND
  RFU4  = TP_CHD_CPU0_DIMM1_FRU_4
  CA1_B  = M_D_CPU0_SB_CA<1>
  VSS96  = GND
  CA3_B  = M_D_CPU0_SB_CA<3>
  VSS97  = GND
  CA5_B  = M_D_CPU0_SB_CA<5>
  VSS98  = GND
  PAR_B  = M_D_CPU0_SB_PAR
  VSS99  = GND
  CS1_B_N  = M_D_CPU0_SB_CS_N<1>
  VSS100  = GND
  RFU5  = TP_CHD_CPU0_DIMM1_FRU_5
  RFU6  = TP_CHD_CPU0_DIMM1_FRU_6
  VSS101  = GND
  CB6_B  = M_D_CPU0_SB_CB<6>
  VSS102  = GND
  CB7_B  = M_D_CPU0_SB_CB<7>
  VSS103  = GND
  DQS4_B_C  = M_D_CPU0_SB_DQS_DN<4>
  DQS4_B_T  = M_D_CPU0_SB_DQS_DP<4>
  VSS104  = GND
  CB2_B  = M_D_CPU0_SB_CB<2>
  VSS105  = GND
  CB3_B  = M_D_CPU0_SB_CB<3>
  VSS106  = GND
  DQ2_B  = M_D_CPU0_SB_DQ<2>
  VSS107  = GND
  DQ3_B  = M_D_CPU0_SB_DQ<3>
  VSS108  = GND
  \dqs5_b_c||tdqs5_b_c\  = M_D_CPU0_SB_DQS_DN<5>
  \dqs5_b_t||tdqs5_b_t\  = M_D_CPU0_SB_DQS_DP<5>
  VSS109  = GND
  DQ6_B  = M_D_CPU0_SB_DQ<6>
  VSS110  = GND
  DQ7_B  = M_D_CPU0_SB_DQ<7>
  VSS111  = GND
  DQ10_B  = M_D_CPU0_SB_DQ<10>
  VSS112  = GND
  DQ11_B  = M_D_CPU0_SB_DQ<11>
  VSS113  = GND
  \dqs6_b_c||tdqs6_b_c\  = M_D_CPU0_SB_DQS_DN<6>
  \dqs6_b_t||tdqs6_b_t\  = M_D_CPU0_SB_DQS_DP<6>
  VSS114  = GND
  DQ14_B  = M_D_CPU0_SB_DQ<14>
  VSS115  = GND
  DQ15_B  = M_D_CPU0_SB_DQ<15>
  VSS116  = GND
  DQ18_B  = M_D_CPU0_SB_DQ<18>
  VSS117  = GND
  DQ19_B  = M_D_CPU0_SB_DQ<19>
  VSS118  = GND
  \dqs7_b_c||tdqs7_b_c\  = M_D_CPU0_SB_DQS_DN<7>
  \dqs7_b_t||tdqs7_b_t\  = M_D_CPU0_SB_DQS_DP<7>
  VSS119  = GND
  DQ22_B  = M_D_CPU0_SB_DQ<22>
  VSS120  = GND
  DQ23_B  = M_D_CPU0_SB_DQ<23>
  VSS121  = GND
  DQ26_B  = M_D_CPU0_SB_DQ<26>
  VSS122  = GND
  DQ27_B  = M_D_CPU0_SB_DQ<27>
  VSS123  = GND
  \dqs8_b_c||tdqs8_b_c\  = M_D_CPU0_SB_DQS_DN<8>
  \dqs8_b_t||tdqs8_b_t\  = M_D_CPU0_SB_DQS_DP<8>
  VSS124  = GND
  DQ30_B  = M_D_CPU0_SB_DQ<30>
  VSS125  = GND
  DQ31_B  = M_D_CPU0_SB_DQ<31>
  VSS126  = GND
  G1  = GND
  G2  = GND
  G3  = GND

(kicad_pcb
	(version 20260206)
	(generator "pcbnew")
	(generator_version "10.0")
	(general
		(thickness 1.6)
		(legacy_teardrops no)
	)
	(paper "A4")
	(title_block
		(title "03242023_DA0F0TMBIJ0_F0T_Motherboard_J_brd_V01_OCP.brd")
		(comment 1 "Grand Teton / footprint 37 of 6105 (J7), pads 46-91 of 291")
	)
	(layers
		(0 "F.Cu" signal "TOP")
		(4 "In1.Cu" signal "GND")
		(6 "In2.Cu" signal "IN1")
		(8 "In3.Cu" signal "GND1")
		(10 "In4.Cu" signal "IN2")
		(12 "In5.Cu" signal "GND2")
		(14 "In6.Cu" signal "IN3")
		(16 "In7.Cu" signal "GND3")
		(18 "In8.Cu" signal "VCC")
		(20 "In9.Cu" signal "VCC1")
		(22 "In10.Cu" signal "GND4")
		(24 "In11.Cu" signal "IN4")
		(26 "In12.Cu" signal "GND5")
		(28 "In13.Cu" signal "IN5")
		(30 "In14.Cu" signal "GND6")
		(32 "In15.Cu" signal "IN6")
		(34 "In16.Cu" signal "GND7")
		(2 "B.Cu" signal "BOTTOM")
		(9 "F.Adhes" user "F.Adhesive")
		(11 "B.Adhes" user "B.Adhesive")
		(13 "F.Paste" user "Package Geometry/Pastemask Top")
		(15 "B.Paste" user "Package Geometry/Pastemask Bottom")
		(5 "F.SilkS" user "Ref Des/Silkscreen Top")
		(7 "B.SilkS" user "Ref Des/Silkscreen Bottom")
		(1 "F.Mask" user "Board Geometry/Soldermask Top")
		(3 "B.Mask" user "Board Geometry/Soldermask Bottom")
		(17 "Dwgs.User" user "User.Drawings")
		(19 "Cmts.User" user "User.Comments")
		(21 "Eco1.User" user "User.Eco1")
		(23 "Eco2.User" user "User.Eco2")
		(25 "Edge.Cuts" user "Board Geometry/Outline")
		(27 "Margin" user)
		(31 "F.CrtYd" user "Package Geometry/Place Bound Top")
		(29 "B.CrtYd" user "Package Geometry/Place Bound Bottom")
		(35 "F.Fab" user "Ref Des/Assembly Top")
		(33 "B.Fab" user "Ref Des/Assembly Bottom")
	)
	(footprint ""
		(layer "F.Cu")
		(at 258.130548 -258.091686)
		(property "Reference" "J7"
			(at -3.683 -81.702148 0)
			(unlocked yes)
			(layer "F.SilkS")
			(effects
				(font
					(size 0.7874 0.5842)
					(thickness 0.1524)
				)
				(justify left)
			)
		)
		(property "Value" ""
			(at 0 0 0)
			(layer "F.Fab")
			(effects
				(font
					(size 1.27 1.27)
				)
			)
		)
		(duplicate_pad_numbers_are_jumpers no)
		(pad "46" smd rect
			(at -2.050034 -25.07488 270)
			(size 0.519938 1.4986)
			(layers "F.Cu" "F.Mask" "F.Paste")
			(net "GND")
		)
		(pad "47" smd rect
			(at -2.050034 -24.224996 270)
			(size 0.519938 1.4986)
			(layers "F.Cu" "F.Mask" "F.Paste")
			(net "M_D_CPU0_SA_DQ<28>")
		)
		(pad "48" smd rect
			(at -2.050034 -23.375112 270)
			(size 0.519938 1.4986)
			(layers "F.Cu" "F.Mask" "F.Paste")
			(net "GND")
		)
		(pad "49" smd rect
			(at -2.050034 -22.524974 270)
			(size 0.519938 1.4986)
			(layers "F.Cu" "F.Mask" "F.Paste")
			(net "M_D_CPU0_SA_DQ<29>")
		)
		(pad "50" smd rect
			(at -2.050034 -21.67509 270)
			(size 0.519938 1.4986)
			(layers "F.Cu" "F.Mask" "F.Paste")
			(net "GND")
		)
		(pad "51" smd rect
			(at -2.050034 -20.824952 270)
			(size 0.519938 1.4986)
			(layers "F.Cu" "F.Mask" "F.Paste")
			(net "M_D_CPU0_SA_CB<0>")
		)
		(pad "52" smd rect
			(at -2.050034 -19.975068 270)
			(size 0.519938 1.4986)
			(layers "F.Cu" "F.Mask" "F.Paste")
			(net "GND")
		)
		(pad "53" smd rect
			(at -2.050034 -19.12493 270)
			(size 0.519938 1.4986)
			(layers "F.Cu" "F.Mask" "F.Paste")
			(net "M_D_CPU0_SA_CB<1>")
		)
		(pad "54" smd rect
			(at -2.050034 -18.275046 270)
			(size 0.519938 1.4986)
			(layers "F.Cu" "F.Mask" "F.Paste")
			(net "GND")
		)
		(pad "55" smd rect
			(at -2.050034 -17.424908 270)
			(size 0.519938 1.4986)
			(layers "F.Cu" "F.Mask" "F.Paste")
			(net "M_D_CPU0_SA_DQS_DP<4>")
		)
		(pad "56" smd rect
			(at -2.050034 -16.575024 270)
			(size 0.519938 1.4986)
			(layers "F.Cu" "F.Mask" "F.Paste")
			(net "M_D_CPU0_SA_DQS_DN<4>")
		)
		(pad "57" smd rect
			(at -2.050034 -15.724886 270)
			(size 0.519938 1.4986)
			(layers "F.Cu" "F.Mask" "F.Paste")
			(net "GND")
		)
		(pad "58" smd rect
			(at -2.050034 -14.875002 270)
			(size 0.519938 1.4986)
			(layers "F.Cu" "F.Mask" "F.Paste")
			(net "M_D_CPU0_SA_CB<4>")
		)
		(pad "59" smd rect
			(at -2.050034 -14.025118 270)
			(size 0.519938 1.4986)
			(layers "F.Cu" "F.Mask" "F.Paste")
			(net "GND")
		)
		(pad "60" smd rect
			(at -2.050034 -13.17498 270)
			(size 0.519938 1.4986)
			(layers "F.Cu" "F.Mask" "F.Paste")
			(net "M_D_CPU0_SA_CB<5>")
		)
		(pad "61" smd rect
			(at -2.050034 -12.325096 270)
			(size 0.519938 1.4986)
			(layers "F.Cu" "F.Mask" "F.Paste")
			(net "GND")
		)
		(pad "62" smd rect
			(at -2.050034 -11.474958 270)
			(size 0.519938 1.4986)
			(layers "F.Cu" "F.Mask" "F.Paste")
			(net "M_D_CPU0_ALERT_N")
		)
		(pad "63" smd rect
			(at -2.050034 -10.625074 270)
			(size 0.519938 1.4986)
			(layers "F.Cu" "F.Mask" "F.Paste")
			(net "GND")
		)
		(pad "64" smd rect
			(at -2.050034 -9.774936 270)
			(size 0.519938 1.4986)
			(layers "F.Cu" "F.Mask" "F.Paste")
			(net "M_D_CPU0_SA_CS_N<0>")
		)
		(pad "65" smd rect
			(at -2.050034 -8.925052 270)
			(size 0.519938 1.4986)
			(layers "F.Cu" "F.Mask" "F.Paste")
			(net "GND")
		)
		(pad "66" smd rect
			(at -2.050034 -8.074914 270)
			(size 0.519938 1.4986)
			(layers "F.Cu" "F.Mask" "F.Paste")
			(net "M_D_CPU0_SA_CA<0>")
		)
		(pad "67" smd rect
			(at -2.050034 -7.22503 270)
			(size 0.519938 1.4986)
			(layers "F.Cu" "F.Mask" "F.Paste")
			(net "GND")
		)
		(pad "68" smd rect
			(at -2.050034 -6.374892 270)
			(size 0.519938 1.4986)
			(layers "F.Cu" "F.Mask" "F.Paste")
			(net "M_D_CPU0_SA_CA<2>")
		)
		(pad "69" smd rect
			(at -2.050034 -5.525008 270)
			(size 0.519938 1.4986)
			(layers "F.Cu" "F.Mask" "F.Paste")
			(net "GND")
		)
		(pad "70" smd rect
			(at -2.050034 -4.675124 270)
			(size 0.519938 1.4986)
			(layers "F.Cu" "F.Mask" "F.Paste")
			(net "M_D_CPU0_SA_CA<4>")
		)
		(pad "71" smd rect
			(at -2.050034 -3.824986 270)
			(size 0.519938 1.4986)
			(layers "F.Cu" "F.Mask" "F.Paste")
			(net "GND")
		)
		(pad "72" smd rect
			(at -2.050034 -2.975102 270)
			(size 0.519938 1.4986)
			(layers "F.Cu" "F.Mask" "F.Paste")
			(net "M_D_CPU0_SA_CA<6>")
		)
		(pad "73" smd rect
			(at -2.050034 -2.124964 270)
			(size 0.519938 1.4986)
			(layers "F.Cu" "F.Mask" "F.Paste")
			(net "GND")
		)
		(pad "74" smd rect
			(at -2.050034 -1.27508 270)
			(size 0.519938 1.4986)
			(layers "F.Cu" "F.Mask" "F.Paste")
			(net "M_D_CPU0_SA_PAR")
		)
		(pad "75" smd rect
			(at -2.050034 -0.424942 270)
			(size 0.519938 1.4986)
			(layers "F.Cu" "F.Mask" "F.Paste")
			(net "GND")
		)
		(pad "76" smd rect
			(at -2.050034 5.525008 270)
			(size 0.519938 1.4986)
			(layers "F.Cu" "F.Mask" "F.Paste")
			(net "M_D_CPU0_SB_CA<0>")
		)
		(pad "77" smd rect
			(at -2.050034 6.374892 270)
			(size 0.519938 1.4986)
			(layers "F.Cu" "F.Mask" "F.Paste")
			(net "GND")
		)
		(pad "78" smd rect
			(at -2.050034 7.22503 270)
			(size 0.519938 1.4986)
			(layers "F.Cu" "F.Mask" "F.Paste")
			(net "M_D_CPU0_SB_CA<2>")
		)
		(pad "79" smd rect
			(at -2.050034 8.074914 270)
			(size 0.519938 1.4986)
			(layers "F.Cu" "F.Mask" "F.Paste")
			(net "GND")
		)
		(pad "80" smd rect
			(at -2.050034 8.925052 270)
			(size 0.519938 1.4986)
			(layers "F.Cu" "F.Mask" "F.Paste")
			(net "M_D_CPU0_SB_CA<4>")
		)
		(pad "81" smd rect
			(at -2.050034 9.774936 270)
			(size 0.519938 1.4986)
			(layers "F.Cu" "F.Mask" "F.Paste")
			(net "GND")
		)
		(pad "82" smd rect
			(at -2.050034 10.625074 270)
			(size 0.519938 1.4986)
			(layers "F.Cu" "F.Mask" "F.Paste")
			(net "M_D_CPU0_SB_CA<6>")
		)
		(pad "83" smd rect
			(at -2.050034 11.474958 270)
			(size 0.519938 1.4986)
			(layers "F.Cu" "F.Mask" "F.Paste")
			(net "GND")
		)
		(pad "84" smd rect
			(at -2.050034 12.325096 270)
			(size 0.519938 1.4986)
			(layers "F.Cu" "F.Mask" "F.Paste")
			(net "M_D_CPU0_SB_CS_N<0>")
		)
		(pad "85" smd rect
			(at -2.050034 13.17498 270)
			(size 0.519938 1.4986)
			(layers "F.Cu" "F.Mask" "F.Paste")
			(net "GND")
		)
		(pad "86" smd rect
			(at -2.050034 14.025118 270)
			(size 0.519938 1.4986)
			(layers "F.Cu" "F.Mask" "F.Paste")
			(net "M_D_CPU0_SA_RSP<0>")
		)
		(pad "87" smd rect
			(at -2.050034 14.875002 270)
			(size 0.519938 1.4986)
			(layers "F.Cu" "F.Mask" "F.Paste")
			(net "M_D_CPU0_SB_RSP<0>")
		)
		(pad "88" smd rect
			(at -2.050034 15.724886 270)
			(size 0.519938 1.4986)
			(layers "F.Cu" "F.Mask" "F.Paste")
			(net "GND")
		)
		(pad "89" smd rect
			(at -2.050034 16.575024 270)
			(size 0.519938 1.4986)
			(layers "F.Cu" "F.Mask" "F.Paste")
			(net "M_D_CPU0_SB_CB<4>")
		)
		(pad "90" smd rect
			(at -2.050034 17.424908 270)
			(size 0.519938 1.4986)
			(layers "F.Cu" "F.Mask" "F.Paste")
			(net "GND")
		)
		(pad "91" smd rect
			(at -2.050034 18.275046 270)
			(size 0.519938 1.4986)
			(layers "F.Cu" "F.Mask" "F.Paste")
			(net "M_D_CPU0_SB_CB<5>")
		)
	)
)
